(kicad_pcb
	(version 20241229)
	(generator "pcbnew")
	(generator_version "9.0")
	(general
		(thickness 1.294)
		(legacy_teardrops no)
	)
	(paper "A3")
	(title_block
		(title "Kintex 410T devboard")
		(date "2024-04-03")
		(rev "1.1.2")
		(comment 9 "footprints 20-26 of 975")
	)
	(layers
		(0 "F.Cu" mixed)
		(4 "In1.Cu" power)
		(6 "In2.Cu" power)
		(8 "In3.Cu" mixed)
		(10 "In4.Cu" power)
		(12 "In5.Cu" mixed)
		(14 "In6.Cu" power)
		(16 "In7.Cu" mixed)
		(18 "In8.Cu" power)
		(2 "B.Cu" mixed)
		(9 "F.Adhes" user "F.Adhesive")
		(11 "B.Adhes" user "B.Adhesive")
		(13 "F.Paste" user)
		(15 "B.Paste" user)
		(5 "F.SilkS" user "F.Silkscreen")
		(7 "B.SilkS" user "B.Silkscreen")
		(1 "F.Mask" user)
		(3 "B.Mask" user)
		(17 "Dwgs.User" user "User.Drawings")
		(19 "Cmts.User" user "User.Comments")
		(21 "Eco1.User" user "User.Eco1")
		(23 "Eco2.User" user "User.Eco2")
		(25 "Edge.Cuts" user)
		(27 "Margin" user)
		(31 "F.CrtYd" user "F.Courtyard")
		(29 "B.CrtYd" user "B.Courtyard")
		(35 "F.Fab" user)
		(33 "B.Fab" user)
	)
	(footprint "antmicro-footprints:C_0402_1005Metric"
		(layer "F.Cu")
		(at 256.945 139.835 90)
		(descr "Capacitor SMD 0402")
		(tags "capacitor SMD 0402")
		(property "Reference" "C228"
			(at -1.315 -0.495 90)
			(layer "F.SilkS")
			(effects
				(font
					(size 0.7 0.7)
					(thickness 0.15)
				)
				(justify left bottom)
			)
		)
		(property "Value" "C_22p_0402"
			(at 0 1.4 90)
			(layer "F.Fab")
			(effects
				(font
					(size 0.7 0.7)
					(thickness 0.15)
				)
				(justify left bottom)
			)
		)
		(property "Description" "SMD Multilayer Ceramic Capacitor, 22 pF, 50 V, 0402 [1005 Metric], ± 5%, C0G / NP0, CC Series"
			(at 0 0 90)
			(layer "F.Fab")
			(hide yes)
			(effects
				(font
					(size 1.27 1.27)
					(thickness 0.15)
				)
			)
		)
		(property "Author" "Antmicro"
			(at 396.78 -117.11 0)
			(layer "F.Fab")
			(hide yes)
			(effects
				(font
					(size 1 1)
					(thickness 0.15)
				)
			)
		)
		(property "Dielectric" ""
			(at 396.78 -117.11 0)
			(layer "F.Fab")
			(hide yes)
			(effects
				(font
					(size 1 1)
					(thickness 0.15)
				)
			)
		)
		(property "License" "Apache-2.0"
			(at 396.78 -117.11 0)
			(layer "F.Fab")
			(hide yes)
			(effects
				(font
					(size 1 1)
					(thickness 0.15)
				)
			)
		)
		(property "MPN" "CC0402JRNPO9BN220"
			(at 396.78 -117.11 0)
			(layer "F.Fab")
			(hide yes)
			(effects
				(font
					(size 1 1)
					(thickness 0.15)
				)
			)
		)
		(property "Manufacturer" "YAGEO"
			(at 396.78 -117.11 0)
			(layer "F.Fab")
			(hide yes)
			(effects
				(font
					(size 1 1)
					(thickness 0.15)
				)
			)
		)
		(property "Val" "22p"
			(at 396.78 -117.11 0)
			(layer "F.Fab")
			(hide yes)
			(effects
				(font
					(size 1 1)
					(thickness 0.15)
				)
			)
		)
		(property "Voltage" ""
			(at 396.78 -117.11 0)
			(layer "F.Fab")
			(hide yes)
			(effects
				(font
					(size 1 1)
					(thickness 0.15)
				)
			)
		)
		(sheetname "USB PHY")
		(sheetfile "usb-phy.kicad_sch")
		(attr smd)
		(fp_rect
			(start -0.925 -0.47)
			(end 0.925 0.47)
			(stroke
				(width 0.05)
				(type default)
			)
			(fill no)
			(layer "F.CrtYd")
		)
		(fp_line
			(start 0.504 -0.25)
			(end 0.504 0.248)
			(stroke
				(width 0.15)
				(type solid)
			)
			(layer "F.Fab")
		)
		(fp_line
			(start -0.494 -0.25)
			(end 0.504 -0.25)
			(stroke
				(width 0.15)
				(type solid)
			)
			(layer "F.Fab")
		)
		(fp_line
			(start 0.504 0.248)
			(end -0.494 0.248)
			(stroke
				(width 0.15)
				(type solid)
			)
			(layer "F.Fab")
		)
		(fp_line
			(start -0.494 0.248)
			(end -0.494 -0.25)
			(stroke
				(width 0.15)
				(type solid)
			)
			(layer "F.Fab")
		)
		(pad "1" smd roundrect
			(at -0.48 0 90)
			(size 0.59 0.64)
			(layers "F.Cu" "F.Mask" "F.Paste")
			(roundrect_rratio 0.25)
			(net 1 "GND")
			(pintype "passive")
		)
		(pad "2" smd roundrect
			(at 0.48 0 90)
			(size 0.59 0.64)
			(layers "F.Cu" "F.Mask" "F.Paste")
			(roundrect_rratio 0.25)
			(net 710 "/USB PHY/FTDI_XI")
			(pintype "passive")
		)
	)
	(footprint "antmicro-footprints:FB_0402_1005Metric"
		(layer "F.Cu")
		(at 152.5 148.15 180)
		(descr "Ferrite Bead SMD 0402")
		(tags "ferrite bead SMD 0402")
		(property "Reference" "FB11"
			(at 1.25 -1.25 180)
			(layer "F.SilkS")
			(effects
				(font
					(size 0.7 0.7)
					(thickness 0.15)
				)
				(justify left bottom)
			)
		)
		(property "Value" "FB_120Z_1.3A_Murata-BLM15PD_0402"
			(at 0 1.4 180)
			(layer "F.Fab")
			(effects
				(font
					(size 0.7 0.7)
					(thickness 0.15)
				)
				(justify left bottom)
			)
		)
		(property "Description" "Ferrite Bead, 0402 [1005 Metric], 120 ohm, 1.3 A, BLM15PD, 0.09 ohm, ± 25%, DC power line"
			(at 0 0 180)
			(layer "F.Fab")
			(hide yes)
			(effects
				(font
					(size 1.27 1.27)
					(thickness 0.15)
				)
			)
		)
		(property "Author" "Antmicro"
			(at 305 296.3 0)
			(layer "F.Fab")
			(hide yes)
			(effects
				(font
					(size 1 1)
					(thickness 0.15)
				)
			)
		)
		(property "Current" ""
			(at 305 296.3 0)
			(layer "F.Fab")
			(hide yes)
			(effects
				(font
					(size 1 1)
					(thickness 0.15)
				)
			)
		)
		(property "License" "Apache-2.0"
			(at 305 296.3 0)
			(layer "F.Fab")
			(hide yes)
			(effects
				(font
					(size 1 1)
					(thickness 0.15)
				)
			)
		)
		(property "MPN" "BLM15PD121SN1D"
			(at 305 296.3 0)
			(layer "F.Fab")
			(hide yes)
			(effects
				(font
					(size 1 1)
					(thickness 0.15)
				)
			)
		)
		(property "Manufacturer" "Murata"
			(at 305 296.3 0)
			(layer "F.Fab")
			(hide yes)
			(effects
				(font
					(size 1 1)
					(thickness 0.15)
				)
			)
		)
		(property "Val" "120Z/1.3A"
			(at 305 296.3 0)
			(layer "F.Fab")
			(hide yes)
			(effects
				(font
					(size 1 1)
					(thickness 0.15)
				)
			)
		)
		(sheetname "DC-DC Converters")
		(sheetfile "dc-dc.kicad_sch")
		(attr smd)
		(fp_rect
			(start -0.925 -0.47)
			(end 0.925 0.47)
			(stroke
				(width 0.05)
				(type default)
			)
			(fill no)
			(layer "F.CrtYd")
		)
		(fp_rect
			(start -0.5 -0.25)
			(end 0.5 0.25)
			(stroke
				(width 0.15)
				(type solid)
			)
			(fill no)
			(layer "F.Fab")
		)
		(pad "1" smd roundrect
			(at -0.48 0 180)
			(size 0.59 0.64)
			(layers "F.Cu" "F.Mask" "F.Paste")
			(roundrect_rratio 0.25)
			(net 24 "+3V3")
			(pintype "passive")
		)
		(pad "2" smd roundrect
			(at 0.48 0 180)
			(size 0.59 0.64)
			(layers "F.Cu" "F.Mask" "F.Paste")
			(roundrect_rratio 0.25)
			(net 742 "/DC-DC Converters/1V85_VIN")
			(pintype "passive")
		)
	)
	(footprint "antmicro-footprints:R_0402_1005Metric"
		(layer "F.Cu")
		(at 194.6 165.649 -90)
		(descr "Resistor SMD 0402")
		(tags "resistor SMD 0402")
		(property "Reference" "R327"
			(at 4.851 -2.225 270)
			(layer "F.SilkS")
			(effects
				(font
					(size 0.7 0.7)
					(thickness 0.15)
				)
				(justify left bottom)
			)
		)
		(property "Value" "R_10k_0402"
			(at 0 1.4 270)
			(layer "F.Fab")
			(effects
				(font
					(size 0.7 0.7)
					(thickness 0.15)
				)
				(justify left bottom)
			)
		)
		(property "Description" "SMD Chip Resistor, 10 kohm, ± 1%, 62.5 mW, 0402 [1005 Metric], Thick Film, General Purpose"
			(at 0 0 270)
			(layer "F.Fab")
			(hide yes)
			(effects
				(font
					(size 1.27 1.27)
					(thickness 0.15)
				)
			)
		)
		(property "Author" "Antmicro"
			(at 28.951 360.249 0)
			(layer "F.Fab")
			(hide yes)
			(effects
				(font
					(size 1 1)
					(thickness 0.15)
				)
			)
		)
		(property "License" "Apache-2.0"
			(at 28.951 360.249 0)
			(layer "F.Fab")
			(hide yes)
			(effects
				(font
					(size 1 1)
					(thickness 0.15)
				)
			)
		)
		(property "MPN" "CR0402-FX-1002GLF"
			(at 28.951 360.249 0)
			(layer "F.Fab")
			(hide yes)
			(effects
				(font
					(size 1 1)
					(thickness 0.15)
				)
			)
		)
		(property "Manufacturer" "Bourns"
			(at 28.951 360.249 0)
			(layer "F.Fab")
			(hide yes)
			(effects
				(font
					(size 1 1)
					(thickness 0.15)
				)
			)
		)
		(property "Tolerance" "1%"
			(at 28.951 360.249 0)
			(layer "F.Fab")
			(hide yes)
			(effects
				(font
					(size 1 1)
					(thickness 0.15)
				)
			)
		)
		(property "Val" "10k"
			(at 28.951 360.249 0)
			(layer "F.Fab")
			(hide yes)
			(effects
				(font
					(size 1 1)
					(thickness 0.15)
				)
			)
		)
		(sheetname "DC-DC Converters")
		(sheetfile "dc-dc.kicad_sch")
		(attr smd)
		(fp_rect
			(start -0.925 -0.47)
			(end 0.925 0.47)
			(stroke
				(width 0.05)
				(type default)
			)
			(fill no)
			(layer "F.CrtYd")
		)
		(fp_rect
			(start -0.5 -0.25)
			(end 0.5 0.25)
			(stroke
				(width 0.15)
				(type solid)
			)
			(fill no)
			(layer "F.Fab")
		)
		(pad "1" smd roundrect
			(at -0.48 0 270)
			(size 0.59 0.64)
			(layers "F.Cu" "F.Mask" "F.Paste")
			(roundrect_rratio 0.25)
			(net 970 "/DC-DC Converters/1V0_FB")
			(pintype "passive")
		)
		(pad "2" smd roundrect
			(at 0.48 0 270)
			(size 0.59 0.64)
			(layers "F.Cu" "F.Mask" "F.Paste")
			(roundrect_rratio 0.25)
			(net 1230 "Net-(C364-Pad1)")
			(pintype "passive")
		)
	)
	(footprint "antmicro-footprints:NetTie-2_SMD_Pad0.127mm"
		(layer "F.Cu")
		(at 246.5 143.602 -90)
		(descr "Net tie, 2 pin, 0.127mm  SMD pads")
		(tags "net tie")
		(property "Reference" "NT23"
			(at -0.128 -1.345 270)
			(layer "F.SilkS")
			(hide yes)
			(effects
				(font
					(size 0.7 0.7)
					(thickness 0.15)
				)
				(justify left bottom)
			)
		)
		(property "Value" "Net-Tie_2"
			(at 0 1.199 270)
			(layer "F.Fab")
			(effects
				(font
					(size 0.7 0.7)
					(thickness 0.15)
				)
				(justify left bottom)
			)
		)
		(property "Description" "Net tie, 2 pins"
			(at 0 0 270)
			(layer "F.Fab")
			(hide yes)
			(effects
				(font
					(size 1.27 1.27)
					(thickness 0.15)
				)
			)
		)
		(property "Author" "Antmicro"
			(at 102.898 390.102 0)
			(layer "F.Fab")
			(hide yes)
			(effects
				(font
					(size 1 1)
					(thickness 0.15)
				)
			)
		)
		(property "License" "Apache-2.0"
			(at 102.898 390.102 0)
			(layer "F.Fab")
			(hide yes)
			(effects
				(font
					(size 1 1)
					(thickness 0.15)
				)
			)
		)
		(property "MPN" ""
			(at 102.898 390.102 0)
			(layer "F.Fab")
			(hide yes)
			(effects
				(font
					(size 1 1)
					(thickness 0.15)
				)
			)
		)
		(property "Manufacturer" ""
			(at 102.898 390.102 0)
			(layer "F.Fab")
			(hide yes)
			(effects
				(font
					(size 1 1)
					(thickness 0.15)
				)
			)
		)
		(sheetname "Supervisior MCU")
		(sheetfile "supervisor-mcu.kicad_sch")
		(attr exclude_from_pos_files)
		(net_tie_pad_groups "1, 2")
		(fp_poly
			(pts
				(xy -0.0635 -0.0635) (xy 0.0625 -0.0635) (xy 0.0625 0.0635) (xy -0.0635 0.0635)
			)
			(stroke
				(width 0)
				(type solid)
			)
			(fill yes)
			(layer "F.Cu")
		)
		(pad "1" smd roundrect
			(at -0.127 0 90)
			(size 0.127 0.127)
			(layers "F.Cu")
			(roundrect_rratio 0.5)
			(chamfer_ratio 0)
			(chamfer top_left bottom_left)
			(net 1338 "/I2C.SCL")
			(pinfunction "1")
			(pintype "passive")
		)
		(pad "2" smd roundrect
			(at 0.126 0 270)
			(size 0.127 0.127)
			(layers "F.Cu")
			(roundrect_rratio 0.5)
			(chamfer_ratio 0)
			(chamfer top_left bottom_left)
			(net 1339 "/SUP_MCU.SCL")
			(pinfunction "2")
			(pintype "passive")
		)
	)
	(footprint "antmicro-footprints:R_0402_1005Metric"
		(layer "F.Cu")
		(at 254.899 96 180)
		(descr "Resistor SMD 0402")
		(tags "resistor SMD 0402")
		(property "Reference" "R343"
			(at 1.999 1.6 180)
			(layer "F.SilkS")
			(effects
				(font
					(size 0.7 0.7)
					(thickness 0.15)
				)
				(justify left bottom)
			)
		)
		(property "Value" "R_10k_0402"
			(at 0 1.4 180)
			(layer "F.Fab")
			(effects
				(font
					(size 0.7 0.7)
					(thickness 0.15)
				)
				(justify left bottom)
			)
		)
		(property "Description" "SMD Chip Resistor, 10 kohm, ± 1%, 62.5 mW, 0402 [1005 Metric], Thick Film, General Purpose"
			(at 0 0 180)
			(layer "F.Fab")
			(hide yes)
			(effects
				(font
					(size 1.27 1.27)
					(thickness 0.15)
				)
			)
		)
		(property "Author" "Antmicro"
			(at 509.798 192 0)
			(layer "F.Fab")
			(hide yes)
			(effects
				(font
					(size 1 1)
					(thickness 0.15)
				)
			)
		)
		(property "License" "Apache-2.0"
			(at 509.798 192 0)
			(layer "F.Fab")
			(hide yes)
			(effects
				(font
					(size 1 1)
					(thickness 0.15)
				)
			)
		)
		(property "MPN" "CR0402-FX-1002GLF"
			(at 509.798 192 0)
			(layer "F.Fab")
			(hide yes)
			(effects
				(font
					(size 1 1)
					(thickness 0.15)
				)
			)
		)
		(property "Manufacturer" "Bourns"
			(at 509.798 192 0)
			(layer "F.Fab")
			(hide yes)
			(effects
				(font
					(size 1 1)
					(thickness 0.15)
				)
			)
		)
		(property "Tolerance" "1%"
			(at 509.798 192 0)
			(layer "F.Fab")
			(hide yes)
			(effects
				(font
					(size 1 1)
					(thickness 0.15)
				)
			)
		)
		(property "Val" "10k"
			(at 509.798 192 0)
			(layer "F.Fab")
			(hide yes)
			(effects
				(font
					(size 1 1)
					(thickness 0.15)
				)
			)
		)
		(sheetname "USB PHY")
		(sheetfile "usb-phy.kicad_sch")
		(attr smd)
		(fp_rect
			(start -0.925 -0.47)
			(end 0.925 0.47)
			(stroke
				(width 0.05)
				(type default)
			)
			(fill no)
			(layer "F.CrtYd")
		)
		(fp_rect
			(start -0.5 -0.25)
			(end 0.5 0.25)
			(stroke
				(width 0.15)
				(type solid)
			)
			(fill no)
			(layer "F.Fab")
		)
		(pad "1" smd roundrect
			(at -0.48 0 180)
			(size 0.59 0.64)
			(layers "F.Cu" "F.Mask" "F.Paste")
			(roundrect_rratio 0.25)
			(net 703 "+5V")
			(pintype "passive")
		)
		(pad "2" smd roundrect
			(at 0.48 0 180)
			(size 0.59 0.64)
			(layers "F.Cu" "F.Mask" "F.Paste")
			(roundrect_rratio 0.25)
			(net 637 "/USB PHY/USB_HOST_VBUS_FLG")
			(pintype "passive")
		)
	)
	(footprint "antmicro-footprints:C_0402_1005Metric"
		(layer "F.Cu")
		(at 191.925 176.699 -90)
		(descr "Capacitor SMD 0402")
		(tags "capacitor SMD 0402")
		(property "Reference" "C205"
			(at 4.401 -4.575 180)
			(layer "F.SilkS")
			(effects
				(font
					(size 0.7 0.7)
					(thickness 0.15)
				)
				(justify right bottom)
			)
		)
		(property "Value" "C_100n_0402"
			(at 0 1.4 90)
			(layer "F.Fab")
			(effects
				(font
					(size 0.7 0.7)
					(thickness 0.15)
				)
				(justify right bottom)
			)
		)
		(property "Description" "SMD Multilayer Ceramic Capacitor, 0.1 µF, 50 V, 0402 [1005 Metric], ± 10%, X5R, GRM Series"
			(at 0 0 270)
			(layer "F.Fab")
			(hide yes)
			(effects
				(font
					(size 1.27 1.27)
					(thickness 0.15)
				)
			)
		)
		(property "Author" "Antmicro"
			(at 15.226 368.624 0)
			(layer "F.Fab")
			(hide yes)
			(effects
				(font
					(size 1 1)
					(thickness 0.15)
				)
			)
		)
		(property "Dielectric" "X5R"
			(at 15.226 368.624 0)
			(layer "F.Fab")
			(hide yes)
			(effects
				(font
					(size 1 1)
					(thickness 0.15)
				)
			)
		)
		(property "License" "Apache-2.0"
			(at 15.226 368.624 0)
			(layer "F.Fab")
			(hide yes)
			(effects
				(font
					(size 1 1)
					(thickness 0.15)
				)
			)
		)
		(property "MPN" "GRM155R61H104KE14D"
			(at 15.226 368.624 0)
			(layer "F.Fab")
			(hide yes)
			(effects
				(font
					(size 1 1)
					(thickness 0.15)
				)
			)
		)
		(property "Manufacturer" "Murata"
			(at 15.226 368.624 0)
			(layer "F.Fab")
			(hide yes)
			(effects
				(font
					(size 1 1)
					(thickness 0.15)
				)
			)
		)
		(property "Val" "100n"
			(at 15.226 368.624 0)
			(layer "F.Fab")
			(hide yes)
			(effects
				(font
					(size 1 1)
					(thickness 0.15)
				)
			)
		)
		(property "Voltage" "50V"
			(at 15.226 368.624 0)
			(layer "F.Fab")
			(hide yes)
			(effects
				(font
					(size 1 1)
					(thickness 0.15)
				)
			)
		)
		(sheetname "Power supply")
		(sheetfile "power-supply.kicad_sch")
		(attr smd)
		(fp_rect
			(start -0.925 -0.47)
			(end 0.925 0.47)
			(stroke
				(width 0.05)
				(type default)
			)
			(fill no)
			(layer "F.CrtYd")
		)
		(fp_line
			(start -0.494 0.248)
			(end -0.494 -0.25)
			(stroke
				(width 0.15)
				(type solid)
			)
			(layer "F.Fab")
		)
		(fp_line
			(start 0.504 0.248)
			(end -0.494 0.248)
			(stroke
				(width 0.15)
				(type solid)
			)
			(layer "F.Fab")
		)
		(fp_line
			(start -0.494 -0.25)
			(end 0.504 -0.25)
			(stroke
				(width 0.15)
				(type solid)
			)
			(layer "F.Fab")
		)
		(fp_line
			(start 0.504 -0.25)
			(end 0.504 0.248)
			(stroke
				(width 0.15)
				(type solid)
			)
			(layer "F.Fab")
		)
		(pad "1" smd roundrect
			(at -0.48 0 270)
			(size 0.59 0.64)
			(layers "F.Cu" "F.Mask" "F.Paste")
			(roundrect_rratio 0.25)
			(net 1 "GND")
			(pintype "passive")
		)
		(pad "2" smd roundrect
			(at 0.48 0 270)
			(size 0.59 0.64)
			(layers "F.Cu" "F.Mask" "F.Paste")
			(roundrect_rratio 0.25)
			(net 956 "/DC-DC Converters/POE_DC")
			(pintype "passive")
		)
	)
	(footprint "antmicro-footprints:TP_SMD_0.75mm"
		(layer "F.Cu")
		(at 163.9625 171.075)
		(property "Reference" "TP7"
			(at 0.3875 0.425 0)
			(layer "F.SilkS")
			(effects
				(font
					(size 0.7 0.7)
					(thickness 0.15)
				)
				(justify left bottom)
			)
		)
		(property "Value" "TP_0.75mm_SMD"
			(at 0 1.2 0)
			(layer "F.Fab")
			(effects
				(font
					(size 0.7 0.7)
					(thickness 0.15)
				)
				(justify left bottom)
			)
		)
		(property "Description" "SMT test point"
			(at 0 0 0)
			(layer "F.Fab")
			(hide yes)
			(effects
				(font
					(size 1.27 1.27)
					(thickness 0.15)
				)
			)
		)
		(property "Author" "Antmicro"
			(at 0 0 0)
			(layer "F.Fab")
			(hide yes)
			(effects
				(font
					(size 1 1)
					(thickness 0.15)
				)
			)
		)
		(property "License" "Apache-2.0"
			(at 0 0 0)
			(layer "F.Fab")
			(hide yes)
			(effects
				(font
					(size 1 1)
					(thickness 0.15)
				)
			)
		)
		(property "MPN" ""
			(at 0 0 0)
			(layer "F.Fab")
			(hide yes)
			(effects
				(font
					(size 1 1)
					(thickness 0.15)
				)
			)
		)
		(property "Manufacturer" ""
			(at 0 0 0)
			(layer "F.Fab")
			(hide yes)
			(effects
				(font
					(size 1 1)
					(thickness 0.15)
				)
			)
		)
		(sheetname "DC-DC Converters")
		(sheetfile "dc-dc.kicad_sch")
		(attr exclude_from_pos_files)
		(pad "1" smd circle
			(at 0 0)
			(size 0.75 0.75)
			(layers "F.Cu" "F.Mask")
			(net 1336 "/I2C.SDA")
			(pinfunction "1")
			(pintype "passive")
		)
	)
)
